# Bryce Canyon_IOM_IOC_Stackup.xlsx — Stack up_16318-2 (pcb-stackup)
|  |  |  |  |  |  | Version |  |  |  |  |  |  |  |  |  |  |  |  |  |  |  |  |  |  |  |  |  |  |  |  |  |  |  |  |  |  |  |  |
| Board Number: |  | 16318-2 |  |  |  | 02 |  |  |  |  |  |  |  |  |  |  |  |  |  |  |  |  |  |  |  |  |  |  |  |  |  |  |  |  |  |  |  |  |
| Project name: |  | Bryce Canyon |  |  |  |  |  |  |  |  |  |  |  |  |  |  |  |  |  |  |  |  |  |  |  |  |  |  |  |  |  |  |  |  |  |  |  |  |
| Model Name: |  | IOM_Broadcom |  |  |  |  |  |  |  |  |  |  |  |  |  |  |  |  |  |  |  |  |  |  |  |  |  |  |  |  |  |  |  |  |  |  |  |  |
| Layer Count: |  | 8 Layer |  |  |  |  |  |  |  |  |  |  |  |  |  |  |  |  |  |  |  |  |  |  |  |  |  |  |  |  |  |  |  |  |  |  |  |  |
| Date: |  | 2017-09-25 00:00:00 |  |  |  |  |  |  |  |  |  |  |  |  |  |  |  |  |  |  |  |  |  |  |  |  |  |  |  |  |  |  |  |  |  |  |  |  |
| Low Loss Material: |  | TU863+VLP (Tg : 180/Td : 375) |  |  |  |  |  |  |  | Single Ended Type(mil) |  |  |  |  | Differential Type(mil) |  |  |  |  |  |  |  |  |  |  |  |  |  |  |  |  |  |  |  |  |  |  |  |
| Gold Finger(Y/N): |  | N |  |  |  |  |  |  | Imp | 50 |  |  |  | Imp | 85 |  |  |  |  |  | 100 |  |  |  |  |  | 97 |  |  |  |  |  | 92 |  |  |  |  |  |
| Customer: |  | <name> |  |  |  |  |  |  | Variation | Inner/Outer+/-5ohm |  |  |  | Variation | Inner/Outer+/-10% |  |  |  |  |  | Inner/Outer+/-10% |  |  |  |  |  | Outer+/-10% |  |  |  |  |  | Outer+/-10% |  |  |  |  |  |
| EE engineer |  | <name> |  |  |  |  |  |  | Bus | MISC./I2C |  |  |  | Bus | PCIe/Clock/USB |  |  |  |  |  | Clock/SATA |  |  |  |  |  | BGA Break out(SAS.SATA) |  |  |  |  |  | BGA Break out(PCIE) |  |  |  |  |  |
| SI Engineer |  | <name> |  |  |  |  |  |  |  |  |  |  |  |  |  |  |  |  |  |  |  |  |  |  |  |  |  |  |  |  |  |  |  |  |  |  |  |  |
|  |  |  |  |  |  |  |  |  | Type | SE |  |  |  | Type | DP |  |  |  |  |  | DP |  |  |  |  |  | DP |  |  |  |  |  | DP |  |  |  |  |  |
| Layer |  |  | Thickness |  | Glass/Copper Style | Er |  | Df(1G) | Layers | 1,3,6,8 |  |  |  | Layers | 1,3,6,8 |  |  |  |  |  | 1,3,6,8 |  |  |  |  |  | 1,8 |  |  |  |  |  | 1,8 |  |  |  |  |  |
|  |  | Cu oz | Wiwynn |  |  | Wiwynn |  |  |  | Wiwynn |  |  |  |  | Wiwynn |  |  |  |  |  | Wiwynn |  |  |  |  |  | Wiwynn |  |  |  |  |  | Wiwynn |  |  |  |  |  |
|  | Mask |  | 0.5 |  |  | 3.4 |  |  |  | Width | Imp | Width | Imp |  | Width | Space | Imp | Width | Space | Imp | Width | Space | Imp | Width | Space | Imp | Width | Space | Imp | Width | Space | Imp | Width | Space | Imp | Width | Space | Imp |
| Top | Signal | 3/8 oz+plating | 1.7 |  |  |  |  |  | S1 | 5(L2) | 50.08 |  |  | S1 | 5.75(L2) | 6.5 | 85.36 |  |  |  | 4.9(L2) | 11.1 | 96.82 |  |  |  | 3.5(L2) | 4 |  |  |  |  | 3.75(L2) | 3.5 |  |  |  |  |
|  | Prepreg |  | 3 |  |  | 3.9 |  |  |  |  |  |  |  |  |  |  |  |  |  |  |  |  |  |  |  |  |  |  |  |  |  |  |  |  |  |  |  |  |
| L2 | GND | 1 oz | 1.3 |  |  |  |  |  | P2 | reference layer |  |  |  | P2 | reference layer |  |  |  |  |  | reference layer |  |  |  |  |  | reference layer |  |  |  |  |  | reference layer |  |  |  |  |  |
|  | Core |  | 4 |  |  | 3.9 |  |  |  |  |  |  |  |  |  |  |  |  |  |  |  |  |  |  |  |  |  |  |  |  |  |  |  |  |  |  |  |  |
| L3 | Signal | 1 oz | 1.3 |  |  |  |  |  | S3 | 5(L2/L4) | 49.28 |  |  | S3 | 5.5(L2/L4) | 7.5 | 84.9 |  |  |  | 4(L2/L4) | 8 | 97.59 |  |  |  |  |  |  |  |  |  |  |  |  |  |  |  |
|  | Prepreg |  | 16.4 |  |  | 4.2 |  |  |  |  |  |  |  |  |  |  |  |  |  |  |  |  |  |  |  |  |  |  |  |  |  |  |  |  |  |  |  |  |
| L4 | POWER | 1 oz | 1.3 |  |  |  |  |  | P4 | reference layer |  |  |  | P4 | reference layer |  |  |  |  |  | reference layer |  |  |  |  |  | reference layer |  |  |  |  |  | reference layer |  |  |  |  |  |
|  | Core |  | 4 |  |  | 3.8 | 0 | 0 |  |  |  |  |  |  |  |  |  |  |  |  |  |  |  |  |  |  |  |  |  |  |  |  |  |  |  |  |  |  |
| L5 | POWER | 1 oz | 1.3 | 0 | 0 |  |  |  | P5 | reference layer |  |  |  | P5 | reference layer |  |  |  |  |  | reference layer |  |  |  |  |  | reference layer |  |  |  |  |  | reference layer |  |  |  |  |  |
|  | Prepreg |  | 16.4 | 0 | 0 | 4.2 | 0 | 0 |  |  |  |  |  |  |  |  |  |  |  |  |  |  |  |  |  |  |  |  |  |  |  |  |  |  |  |  |  |  |
| L6 | Signal | 1 oz | 1.3 | 0 | 0 |  |  |  | S6 | 5(L5/L7) | 49.28 |  |  | S6 | 5.5(L5/L7) | 7.5 | 84.9 |  |  |  | 4(L5/L7) | 8 | 97.59 |  |  |  |  |  |  |  |  |  |  |  |  |  |  |  |
|  | Core |  | 4 | 0 | 0 | 3.9 | 0 | 0 |  |  |  |  |  |  |  |  |  |  |  |  |  |  |  |  |  |  |  |  |  |  |  |  |  |  |  |  |  |  |
| L7 | GND | 1 oz | 1.3 | 0 | 0 |  |  |  | P7 | reference layer |  |  |  | P7 | reference layer |  |  |  |  |  | reference layer |  |  |  |  |  | reference layer |  |  |  |  |  | reference layer |  |  |  |  |  |
|  | Prepreg |  | 3 | 0 | 0 | 3.9 | 0 | 0 |  |  |  |  |  |  |  |  |  |  |  |  |  |  |  |  |  |  |  |  |  |  |  |  |  |  |  |  |  |  |
| Bottom | Signal | 3/8 oz+plating | 1.7 | 0 | 0 |  |  |  | S8 | 5(L7) | 50.08 |  |  | S8 | 5.75(L7) | 6.5 | 85.36 |  |  |  | 4.9(L7) | 11.1 | 96.82 |  |  |  | 3.5(L7) | 4 |  |  |  |  | 3.75(L7) | 3.5 |  |  |  |  |
|  | Mask |  | 0.5 | 0 |  | 3.4 | 0 | 0 |  |  |  |  |  |  |  |  |  |  |  |  |  |  |  |  |  |  |  |  |  |  |  |  |  |  |  |  |  |  |
| Thickness requirement: 1.6 ± 10% mm |  | mil | 62.99999999999999 |  |  |  |  |  |  |  |  |  |  |  |  |  |  |  |  |  |  |  |  |  |  |  |  |  |  |  |  |  |  |  |  |  |  |  |
|  |  | mm | 1.6002032004064006 |  |  |  |  |  |  |  |  |  |  |  |  |  |  |  |  |  |  |  |  |  |  |  |  |  |  |  |  |  |  |  |  |  |  |  |
| Note: | 1. Unit is mil |  |  |  |  |  |  |  |  |  |  |  |  |  |  |  |  |  |  |  |  |  |  |  |  |  |  |  |  |  |  |  |  |  |  |  |  |  |
|  | 2. The total thickness includes trace and solder mask. |  |  |  |  |  |  |  |  |  |  |  |  |  |  |  |  |  |  |  |  |  |  |  |  |  |  |  |  |  |  |  |  |  |  |  |  |  |
|  | 3. Minimum hole copper thickness is 1.0 mil. |  |  |  |  |  |  |  |  |  |  |  |  |  |  |  |  |  |  |  |  |  |  |  |  |  |  |  |  |  |  |  |  |  |  |  |  |  |
|  | 4. Minimum surface copper thickness 1.5 mil. |  |  |  |  |  |  |  |  |  |  |  |  |  |  |  |  |  |  |  |  |  |  |  |  |  |  |  |  |  |  |  |  |  |  |  |  |  |
|  | 5. If there is no controlled impedance line described as the stackup in the gerber file, PCB supplier can ignore this kind of impedance control directly, but need to inform Wiwynn in engineering question(EQ). |  |  |  |  |  |  |  |  |  |  |  |  |  |  |  |  |  |  |  |  |  |  |  |  |  |  |  |  |  |  |  |  |  |  |  |  |  |
|  | 6. PCB test coupon requirement and PCB test note are described in the another sheets. |  |  |  |  |  |  |  |  |  |  |  |  |  |  |  |  |  |  |  |  |  |  |  |  |  |  |  |  |  |  |  |  |  |  |  |  |  |
|  | 7. If there is no "Delta-L" design in gerber file, PCB supplier should design 85 ohm "Delta-L" angle routing coupon and provide the measurement results in FAI report which meet the following criteria: |  |  |  |  |  |  |  |  |  |  |  |  |  |  |  |  |  |  |  |  |  |  |  |  |  |  |  |  |  |  |  |  |  |  |  |  |  |
|  | For low-loss material |  |  |  |  |  |  |  |  |  |  |  |  |  |  |  |  |  |  |  |  |  |  |  |  |  |  |  |  |  |  |  |  |  |  |  |  |  |
|  | (1)   0.55 dB/inch @ 4GHz; 1.05 dB/inch @ 8GHz for microstrip routing |  |  |  |  |  |  |  |  |  |  |  |  |  |  |  |  |  |  |  |  |  |  |  |  |  |  |  |  |  |  |  |  |  |  |  |  |  |
|  | (2)   0.48 dB/inch @ 4GHz; 0.9 dB/inch @ 8GHz for stripline routing |  |  |  |  |  |  |  |  |  |  |  |  |  |  |  |  |  |  |  |  |  |  |  |  |  |  |  |  |  |  |  |  |  |  |  |  |  |
